# S9S_MB_2U (Grand Teton) — schematic netlist excerpt (pin names and nets, part order shuffled) for the footprints in the layout excerpt that follows; sources: Cadence DE-HDL packaged netlist, KiCad conversion of 03242023_DA0F0TMBIJ0_F0T_Motherboard_J_brd_V01_OCP.brd

R770  Q_RES  10K 1% CHIP  pkg 0402LF  page 183 : A = PU_OC5_USB_N ; B = P3V3_AUX
R3724  Q_RES  2.2K 5% CHIP  pkg 0402LF  page 233 : A = P3V3_AUX ; B = SMB_VR_3V3AUX_SDA

(kicad_pcb
	(version 20260206)
	(generator "pcbnew")
	(generator_version "10.0")
	(general
		(thickness 1.6)
		(legacy_teardrops no)
	)
	(paper "A4")
	(title_block
		(title "03242023_DA0F0TMBIJ0_F0T_Motherboard_J_brd_V01_OCP.brd")
		(comment 1 "Grand Teton / footprints 2587-2588 of 6105")
	)
	(layers
		(0 "F.Cu" signal "TOP")
		(4 "In1.Cu" signal "GND")
		(6 "In2.Cu" signal "IN1")
		(8 "In3.Cu" signal "GND1")
		(10 "In4.Cu" signal "IN2")
		(12 "In5.Cu" signal "GND2")
		(14 "In6.Cu" signal "IN3")
		(16 "In7.Cu" signal "GND3")
		(18 "In8.Cu" signal "VCC")
		(20 "In9.Cu" signal "VCC1")
		(22 "In10.Cu" signal "GND4")
		(24 "In11.Cu" signal "IN4")
		(26 "In12.Cu" signal "GND5")
		(28 "In13.Cu" signal "IN5")
		(30 "In14.Cu" signal "GND6")
		(32 "In15.Cu" signal "IN6")
		(34 "In16.Cu" signal "GND7")
		(2 "B.Cu" signal "BOTTOM")
		(9 "F.Adhes" user "F.Adhesive")
		(11 "B.Adhes" user "B.Adhesive")
		(13 "F.Paste" user "Package Geometry/Pastemask Top")
		(15 "B.Paste" user "Package Geometry/Pastemask Bottom")
		(5 "F.SilkS" user "Ref Des/Silkscreen Top")
		(7 "B.SilkS" user "Ref Des/Silkscreen Bottom")
		(1 "F.Mask" user "Board Geometry/Soldermask Top")
		(3 "B.Mask" user "Board Geometry/Soldermask Bottom")
		(17 "Dwgs.User" user "User.Drawings")
		(19 "Cmts.User" user "User.Comments")
		(21 "Eco1.User" user "User.Eco1")
		(23 "Eco2.User" user "User.Eco2")
		(25 "Edge.Cuts" user "Board Geometry/Outline")
		(27 "Margin" user)
		(31 "F.CrtYd" user "Package Geometry/Place Bound Top")
		(29 "B.CrtYd" user "Package Geometry/Place Bound Bottom")
		(35 "F.Fab" user "Ref Des/Assembly Top")
		(33 "B.Fab" user "Ref Des/Assembly Bottom")
	)
	(footprint ""
		(layer "F.Cu")
		(at 339.483446 -27.92603 -90)
		(property "Reference" "R770"
			(at 0 0 270)
			(layer "F.SilkS")
			(hide yes)
			(effects
				(font
					(size 1.27 1.27)
				)
			)
		)
		(property "Value" ""
			(at 0 0 270)
			(layer "F.Fab")
			(effects
				(font
					(size 1.27 1.27)
				)
			)
		)
		(duplicate_pad_numbers_are_jumpers no)
		(fp_line
			(start -0.7874 0.4064)
			(end -0.7874 -0.4064)
			(stroke
				(width 0.1524)
				(type default)
			)
			(layer "F.SilkS")
		)
		(fp_line
			(start 0.7874 0.4064)
			(end -0.7874 0.4064)
			(stroke
				(width 0.1524)
				(type default)
			)
			(layer "F.SilkS")
		)
		(fp_line
			(start -0.7874 -0.4064)
			(end 0.7874 -0.4064)
			(stroke
				(width 0.1524)
				(type default)
			)
			(layer "F.SilkS")
		)
		(fp_line
			(start 0.7874 -0.4064)
			(end 0.7874 0.4064)
			(stroke
				(width 0.1524)
				(type default)
			)
			(layer "F.SilkS")
		)
		(fp_line
			(start -0.67945 0.3048)
			(end -0.67945 -0.305054)
			(stroke
				(width 0.1)
				(type default)
			)
			(layer "F.Fab")
		)
		(fp_line
			(start -0.12065 0.3048)
			(end -0.67945 0.3048)
			(stroke
				(width 0.1)
				(type default)
			)
			(layer "F.Fab")
		)
		(fp_line
			(start 0.120396 0.3048)
			(end 0.120396 0.2794)
			(stroke
				(width 0.1)
				(type default)
			)
			(layer "F.Fab")
		)
		(fp_line
			(start 0.67945 0.3048)
			(end 0.120396 0.3048)
			(stroke
				(width 0.1)
				(type default)
			)
			(layer "F.Fab")
		)
		(fp_line
			(start -0.12065 0.2794)
			(end -0.12065 0.3048)
			(stroke
				(width 0.1)
				(type default)
			)
			(layer "F.Fab")
		)
		(fp_line
			(start 0.120396 0.2794)
			(end -0.12065 0.2794)
			(stroke
				(width 0.1)
				(type default)
			)
			(layer "F.Fab")
		)
		(fp_line
			(start -0.12065 -0.2794)
			(end 0.12065 -0.2794)
			(stroke
				(width 0.1)
				(type default)
			)
			(layer "F.Fab")
		)
		(fp_line
			(start 0.12065 -0.2794)
			(end 0.12065 -0.3048)
			(stroke
				(width 0.1)
				(type default)
			)
			(layer "F.Fab")
		)
		(fp_line
			(start 0.12065 -0.3048)
			(end 0.67945 -0.3048)
			(stroke
				(width 0.1)
				(type default)
			)
			(layer "F.Fab")
		)
		(fp_line
			(start 0.67945 -0.3048)
			(end 0.67945 0.3048)
			(stroke
				(width 0.1)
				(type default)
			)
			(layer "F.Fab")
		)
		(fp_line
			(start -0.67945 -0.305054)
			(end -0.12065 -0.305054)
			(stroke
				(width 0.1)
				(type default)
			)
			(layer "F.Fab")
		)
		(fp_line
			(start -0.12065 -0.305054)
			(end -0.12065 -0.2794)
			(stroke
				(width 0.1)
				(type default)
			)
			(layer "F.Fab")
		)
		(pad "1" smd circle
			(at -0.40005 0 270)
			(size 0 0)
			(layers "F.Cu" "F.Mask" "F.Paste")
			(net "PU_OC5_USB_N")
		)
		(pad "2" smd circle
			(at 0.40005 0 270)
			(size 0 0)
			(layers "F.Cu" "F.Mask" "F.Paste")
			(net "P3V3_AUX")
		)
	)
	(footprint ""
		(layer "F.Cu")
		(at 51.593496 -115.12677)
		(property "Reference" "R3724"
			(at 0 0 0)
			(layer "F.SilkS")
			(hide yes)
			(effects
				(font
					(size 1.27 1.27)
				)
			)
		)
		(property "Value" ""
			(at 0 0 0)
			(layer "F.Fab")
			(effects
				(font
					(size 1.27 1.27)
				)
			)
		)
		(duplicate_pad_numbers_are_jumpers no)
		(fp_line
			(start -0.7874 -0.4064)
			(end 0.7874 -0.4064)
			(stroke
				(width 0.1524)
				(type default)
			)
			(layer "F.SilkS")
		)
		(fp_line
			(start -0.7874 0.4064)
			(end -0.7874 -0.4064)
			(stroke
				(width 0.1524)
				(type default)
			)
			(layer "F.SilkS")
		)
		(fp_line
			(start 0.7874 -0.4064)
			(end 0.7874 0.4064)
			(stroke
				(width 0.1524)
				(type default)
			)
			(layer "F.SilkS")
		)
		(fp_line
			(start 0.7874 0.4064)
			(end -0.7874 0.4064)
			(stroke
				(width 0.1524)
				(type default)
			)
			(layer "F.SilkS")
		)
		(fp_line
			(start -0.67945 -0.305054)
			(end -0.12065 -0.305054)
			(stroke
				(width 0.1)
				(type default)
			)
			(layer "F.Fab")
		)
		(fp_line
			(start -0.67945 0.3048)
			(end -0.67945 -0.305054)
			(stroke
				(width 0.1)
				(type default)
			)
			(layer "F.Fab")
		)
		(fp_line
			(start -0.12065 -0.305054)
			(end -0.12065 -0.2794)
			(stroke
				(width 0.1)
				(type default)
			)
			(layer "F.Fab")
		)
		(fp_line
			(start -0.12065 -0.2794)
			(end 0.12065 -0.2794)
			(stroke
				(width 0.1)
				(type default)
			)
			(layer "F.Fab")
		)
		(fp_line
			(start -0.12065 0.2794)
			(end -0.12065 0.3048)
			(stroke
				(width 0.1)
				(type default)
			)
			(layer "F.Fab")
		)
		(fp_line
			(start -0.12065 0.3048)
			(end -0.67945 0.3048)
			(stroke
				(width 0.1)
				(type default)
			)
			(layer "F.Fab")
		)
		(fp_line
			(start 0.120396 0.2794)
			(end -0.12065 0.2794)
			(stroke
				(width 0.1)
				(type default)
			)
			(layer "F.Fab")
		)
		(fp_line
			(start 0.120396 0.3048)
			(end 0.120396 0.2794)
			(stroke
				(width 0.1)
				(type default)
			)
			(layer "F.Fab")
		)
		(fp_line
			(start 0.12065 -0.3048)
			(end 0.67945 -0.3048)
			(stroke
				(width 0.1)
				(type default)
			)
			(layer "F.Fab")
		)
		(fp_line
			(start 0.12065 -0.2794)
			(end 0.12065 -0.3048)
			(stroke
				(width 0.1)
				(type default)
			)
			(layer "F.Fab")
		)
		(fp_line
			(start 0.67945 -0.3048)
			(end 0.67945 0.3048)
			(stroke
				(width 0.1)
				(type default)
			)
			(layer "F.Fab")
		)
		(fp_line
			(start 0.67945 0.3048)
			(end 0.120396 0.3048)
			(stroke
				(width 0.1)
				(type default)
			)
			(layer "F.Fab")
		)
		(pad "1" smd circle
			(at -0.40005 0)
			(size 0 0)
			(layers "F.Cu" "F.Mask" "F.Paste")
			(net "P3V3_AUX")
		)
		(pad "2" smd circle
			(at 0.40005 0)
			(size 0 0)
			(layers "F.Cu" "F.Mask" "F.Paste")
			(net "SMB_VR_3V3AUX_SDA")
		)
	)
)
